FILE_TYPE = CONNECTIVITY;
{Allegro Design Entry HDL 17.2-2016 S081 (4005846) 1/11/2022}
"PAGE_NUMBER" = 21;
0"NC";
1"P3V3_AUX\g";
2"P3V3_AUX\g";
3"P3V3_AUX\g";
4"P3V3_AUX\g";
5"P3V3_AUX\g";
6"P3V3_AUX\g";
7"P3V3_AUX\g";
8"P3V3_AUX\g";
9"GND\g";
10"GND\g"VOLTAGE"0";
11"GND\g";
12"GND\g";
13"SPI_BMC_HOLD0_N";
14"SMB_BMC_MM16_R1_SDA";
15"EMMC_WP";
16"EMMC_DT6_R";
17"EMMC_DT5_R";
18"EMMC_DT2_R";
19"EMMC_DT1_R";
20"EMMC_DT0_R";
21"BMC_EMMC_RST_N";
22"EMMC_DT4_R";
23"EMMC_DT5_R";
24"EMMC_DT2_R";
25"EMMC_DT3_R";
26"EMMC_DT4_R";
27"EMMC_DT1_R";
28"EMMC_DT0_R";
29"EMMC_DT6_R";
30"BSM_PRSNT_N";
31"SPI_BMC_HOLD1_N";
32"SMB_BMC_MM16_R1_SCL";
33"BMC_EMMC_DT4";
34"BMC_EMMC_DT5";
35"BMC_EMMC_DT6";
36"BMC_EMMC_DT7";
37"SMB_BMC_MM16_R5_SDA";
38"SMB_BMC_MM16_R5_SCL";
39"EMMC_CMD_R";
40"EMMC_DT3_R";
41"SPI_BMC_CS1_FLASH_R_N";
42"RST_SPI_BMC_FLASH_R2_N";
43"SPI_BMC_BOOT_MISO";
44"SPI_BMC_BOOT_MOSI";
45"SPI_BMC_BOOT_CLK";
46"SPI_BMC_BOOT_CS1_R_N";
47"SPI_BMC_BOOT_CS0_R_N";
48"EMMC_DT7_R";
49"SPI_BMC_BT_WP0_N_R";
50"RST_SPI_BMC_FLASH_R1_N";
51"SPI_BMC_IO1_FLASH_R";
52"SPI_BMC_IO0_FLASH_R";
53"SPI_BMC_CLK_FLASH_R";
54"SPI_BMC_CS0_FLASH_R_N";
55"BMC_EMMC_CLK";
56"BMC_EMMC_CMD";
57"BMC_EMMC_DT3";
58"BMC_EMMC_DT1";
59"BMC_EMMC_DT0";
60"BMC_EMMC_DT2";
61"EMMC_CLK_R";
62"SPI_BMC_BT_WP1_N_R";
63"RST_SPI_FLASH_BUF_N";
64"RST_SPI_FLASH_BUF_N";
65"BMC_EMMC_RST_N";
66"BSM_PRSNT_R_N";
67"EMMC_CMD_R";
68"EMMC_DT7_R";
%"Q_RES"
"1","(175,2150)","0","pure_quanta","I100";
;
MATERIAL"EMPTY"
VALUE"33.2"
PACK_TYPE"0402LF"
WATTAGE"1/16W"
CDS_LIB"pure_quanta"
TOLERANCE"1%"
PART_NUMBER"CS03322FB03"
LOCATION"R653"
$SEC"1"
CDS_SEC"1";
"B"
$PN"2"22;
"A"
$PN"1"33;
%"Q_RES"
"1","(175,2200)","0","pure_quanta","I101";
;
MATERIAL"EMPTY"
VALUE"33.2"
PACK_TYPE"0402LF"
WATTAGE"1/16W"
CDS_LIB"pure_quanta"
TOLERANCE"1%"
PART_NUMBER"CS03322FB03"
LOCATION"R652"
$SEC"1"
CDS_SEC"1";
"B"
$PN"2"17;
"A"
$PN"1"34;
%"UNIVERSAL_POWER"
"1","(975,4000)","0","logical_power","I112";
;
HDL_POWER"P3V3_AUX"
CDS_LIB"logical_power";
"A"1;
%"UNIVERSAL_GND"
"1","(4950,3375)","0","logical_power","I124";
;
CDS_LIB"logical_power"
HDL_POWER"GND";
"A"12;
%"Q_RES"
"2","(4950,3650)","0","pure_quanta","I125";
;
VALUE"1K"
MATERIAL"EMPTY"
PART_NUMBER"TMP_QCS21002FB24"
SEC_TYPE"0402LF"
CDS_LIB"pure_quanta"
WATTAGE"1/16W"
TOLERANCE"1%"
PACK_TYPE"0402LF"
LOCATION"R665"
SEC"1";
"A"
$PN"1"49;
"B"
$PN"2"12;
%"Q_RES"
"2","(4675,3650)","0","pure_quanta","I128";
;
MATERIAL"EMPTY"
PART_NUMBER"TMP_QCS21002FB24"
VALUE"1K"
CDS_LIB"pure_quanta"
SEC_TYPE"0402LF"
TOLERANCE"1%"
PACK_TYPE"0402LF"
WATTAGE"1/16W"
LOCATION"R664"
SEC"1";
"A"
$PN"1"62;
"B"
$PN"2"12;
%"UNIVERSAL_POWER"
"1","(3100,4325)","0","logical_power","I139";
;
HDL_POWER"P3V3_AUX"
CDS_LIB"logical_power";
"A"7;
%"UNIVERSAL_GND"
"1","(1900,875)","0","logical_power","I145";
;
CDS_LIB"logical_power"
HDL_POWER"GND";
"A"11;
%"UNIVERSAL_GND"
"1","(1125,900)","0","logical_power","I146";
;
HDL_POWER"GND"
CDS_LIB"logical_power";
"A"10;
%"Q_RES"
"2","(225,3725)","0","pure_quanta","I147";
;
VALUE"4.7K"
MATERIAL"EMPTY"
TOLERANCE"1%"
PART_NUMBER"CS24702FB10"
WATTAGE"1/16W"
PACK_TYPE"0402LF"
CDS_LIB"pure_quanta"
$LOCATION"R543"
CDS_LOCATION"R543"
$SEC"1"
CDS_SEC"1";
"A"
$PN"1"4;
"B"
$PN"2"31;
%"UNIVERSAL_POWER"
"1","(200,3975)","0","logical_power","I148";
;
HDL_POWER"P3V3_AUX"
CDS_LIB"logical_power";
"A"4;
%"Q_RES"
"1","(100,2550)","0","pure_quanta","I156";
;
VALUE"33.2"
MATERIAL"CHIP"
TOLERANCE"1%"
PART_NUMBER"CS03322FB03"
PACK_TYPE"0402LF"
WATTAGE"1/16W"
CDS_LIB"pure_quanta"
SEC_TYPE"0402LF"
$LOCATION"R850"
CDS_LOCATION"R850"
SEC"1";
"B"
$PN"2"14;
"A"
$PN"1"37;
%"Q_RES"
"1","(100,2600)","0","pure_quanta","I157";
;
VALUE"33.2"
MATERIAL"CHIP"
SEC_TYPE"0402LF"
CDS_LIB"pure_quanta"
WATTAGE"1/16W"
PACK_TYPE"0402LF"
PART_NUMBER"CS03322FB03"
TOLERANCE"1%"
$LOCATION"R849"
CDS_LOCATION"R849"
SEC"1";
"B"
$PN"2"32;
"A"
$PN"1"38;
%"UNIVERSAL_POWER"
"1","(-1750,2500)","0","logical_power","I160";
;
HDL_POWER"P3V3_AUX"
CDS_LIB"logical_power";
"A"5;
%"Q_RES"
"1","(100,2450)","0","pure_quanta","I161";
;
VALUE"1K"
MATERIAL"EMPTY"
PACK_TYPE"0402LF"
WATTAGE"1/16W"
TOLERANCE"1%"
PART_NUMBER"CS21002FB06"
CDS_LIB"pure_quanta"
$LOCATION"R867"
CDS_LOCATION"R867"
$SEC"1"
CDS_SEC"1";
"B"
$PN"2"15;
"A"
$PN"1"5;
%"Q_RES"
"2","(500,3725)","0","pure_quanta","I166";
;
PACK_TYPE"0402LF"
MATERIAL"CHIP"
PART_NUMBER"CS31002FB08"
VALUE"10K"
CDS_LIB"pure_quanta"
TOLERANCE"1%"
WATTAGE"1/16W"
$LOCATION"R404"
CDS_LOCATION"R404"
$SEC"1"
CDS_SEC"1";
"A"
$PN"1"3;
"B"
$PN"2"30;
%"Q_RES"
"1","(-150,3200)","0","pure_quanta","I167";
;
VALUE"0"
MATERIAL"CHIP"
CDS_LIB"pure_quanta"
TOLERANCE"5%"
WATTAGE"1/16W"
PACK_TYPE"0402LF"
PART_NUMBER"CS00002JB13"
$LOCATION"R57"
CDS_LOCATION"R57"
$SEC"1"
CDS_SEC"1";
"B"
$PN"2"30;
"A"
$PN"1"66;
%"Q_RES"
"2","(50,3725)","0","pure_quanta","I168";
;
VALUE"4.7K"
MATERIAL"EMPTY"
TOLERANCE"1%"
CDS_LIB"pure_quanta"
PART_NUMBER"CS24702FB10"
WATTAGE"1/16W"
PACK_TYPE"0402LF"
$LOCATION"R58"
CDS_LOCATION"R58"
$SEC"1"
CDS_SEC"1";
"A"
$PN"1"4;
"B"
$PN"2"13;
%"UNIVERSAL_POWER"
"1","(-2950,4450)","0","logical_power","I169";
;
HDL_POWER"P3V3_AUX"
CDS_LIB"logical_power";
"A"2;
%"UNIVERSAL_POWER"
"1","(500,3975)","0","logical_power","I171";
;
HDL_POWER"P3V3_AUX"
CDS_LIB"logical_power";
"A"3;
%"Q_RES"
"2","(-2575,2250)","0","pure_quanta","I172";
;
WATTAGE"1/16W"
PACK_TYPE"0402LF"
MATERIAL"CHIP"
VALUE"4.7K"
TOLERANCE"1%"
CDS_LIB"pure_quanta"
PART_NUMBER"CS24702FB06"
LOCATION"R11"
$SEC"1"
CDS_SEC"1";
"A"
$PN"1"6;
"B"
$PN"2"65;
%"Q_RES"
"2","(2975,3925)","0","pure_quanta","I173";
;
VALUE"4.7K"
MATERIAL"CHIP"
WATTAGE"1/16W"
TOLERANCE"1%"
PACK_TYPE"0402LF"
CDS_LIB"pure_quanta"
PART_NUMBER"CS24702FB06"
LOCATION"R557"
$SEC"1"
CDS_SEC"1";
"A"
$PN"1"7;
"B"
$PN"2"54;
%"Q_RES"
"2","(2850,3925)","0","pure_quanta","I174";
;
VALUE"4.7K"
TOLERANCE"1%"
MATERIAL"CHIP"
WATTAGE"1/16W"
PACK_TYPE"0402LF"
CDS_LIB"pure_quanta"
PART_NUMBER"CS24702FB06"
LOCATION"R558"
$SEC"1"
CDS_SEC"1";
"A"
$PN"1"7;
"B"
$PN"2"41;
%"Q_RES"
"1","(3500,2700)","0","pure_quanta","I175";
;
VALUE"33.2"
MATERIAL"CHIP"
TOLERANCE"1%"
PART_NUMBER"CS03322FB03"
PACK_TYPE"0402LF"
WATTAGE"1/16W"
CDS_LIB"pure_quanta"
LOCATION"R553"
$SEC"1"
CDS_SEC"1";
"B"
$PN"2"47;
"A"
$PN"1"54;
%"Q_RES"
"1","(3500,2750)","0","pure_quanta","I176";
;
VALUE"33.2"
MATERIAL"CHIP"
CDS_LIB"pure_quanta"
WATTAGE"1/16W"
PACK_TYPE"0402LF"
PART_NUMBER"CS03322FB03"
TOLERANCE"1%"
LOCATION"R547"
$SEC"1"
CDS_SEC"1";
"B"
$PN"2"46;
"A"
$PN"1"41;
%"Q_RES"
"1","(3500,2850)","0","pure_quanta","I177";
;
MATERIAL"CHIP"
VALUE"33.2"
CDS_LIB"pure_quanta"
WATTAGE"1/16W"
PACK_TYPE"0402LF"
PART_NUMBER"CS03322FB03"
TOLERANCE"1%"
LOCATION"R549"
$SEC"1"
CDS_SEC"1";
"B"
$PN"2"45;
"A"
$PN"1"53;
%"Q_RES"
"1","(3500,2950)","0","pure_quanta","I178";
;
VALUE"33.2"
MATERIAL"CHIP"
CDS_LIB"pure_quanta"
WATTAGE"1/16W"
PACK_TYPE"0402LF"
PART_NUMBER"CS03322FB03"
TOLERANCE"1%"
LOCATION"R550"
$SEC"1"
CDS_SEC"1";
"B"
$PN"2"44;
"A"
$PN"1"52;
%"Q_RES"
"1","(3500,3000)","0","pure_quanta","I179";
;
MATERIAL"CHIP"
VALUE"33.2"
CDS_LIB"pure_quanta"
TOLERANCE"1%"
PART_NUMBER"CS03322FB03"
PACK_TYPE"0402LF"
WATTAGE"1/16W"
LOCATION"R552"
$SEC"1"
CDS_SEC"1";
"B"
$PN"2"43;
"A"
$PN"1"51;
%"Q_RES"
"1","(3500,3100)","0","pure_quanta","I180";
;
MATERIAL"CHIP"
VALUE"33.2"
TOLERANCE"1%"
PART_NUMBER"CS03322FB03"
PACK_TYPE"0402LF"
WATTAGE"1/16W"
CDS_LIB"pure_quanta"
LOCATION"R562"
$SEC"1"
CDS_SEC"1";
"B"
$PN"2"63;
"A"
$PN"1"50;
%"Q_RES"
"1","(3500,3150)","0","pure_quanta","I181";
;
MATERIAL"EMPTY"
VALUE"33.2"
CDS_LIB"pure_quanta"
WATTAGE"1/16W"
PACK_TYPE"0402LF"
PART_NUMBER"CS03322FB03"
TOLERANCE"1%"
LOCATION"R561"
$SEC"1"
CDS_SEC"1";
"B"
$PN"2"64;
"A"
$PN"1"42;
%"Q_RES"
"2","(3100,3925)","0","pure_quanta","I182";
;
MATERIAL"EMPTY"
WATTAGE"1/16W"
PACK_TYPE"0402LF"
VALUE"4.7K"
TOLERANCE"1%"
CDS_LIB"pure_quanta"
PART_NUMBER"CS24702FB06"
LOCATION"R90"
$SEC"1"
CDS_SEC"1";
"A"
$PN"1"7;
"B"
$PN"2"42;
%"UNIVERSAL_GND"
"1","(4200,-1400)","0","logical_power","I20";
;
CDS_LIB"logical_power"
HDL_POWER"GND";
"A"9;
%"Q_CAP"
"1","(4775,-600)","0","pure_quanta","I21";
;
VALUE"0.1UF"
MATERIAL"EMPTY"
TOLERANCE"10%"
PACK_TYPE"0402"
VOLTAGE"25V"
PART_NUMBER"CH4104K1B00"
CDS_LIB"pure_quanta"
LOCATION"C228"
$SEC"1"
CDS_SEC"1";
"B"
$PN"2"9;
"A"
$PN"1"8;
%"UNIVERSAL_POWER"
"1","(-2575,2500)","0","logical_power","I3";
;
HDL_POWER"P3V3_AUX"
CDS_LIB"logical_power";
"A"6;
%"Q_RES"
"1","(3250,2250)","0","pure_quanta","I33";
;
VALUE"33.2"
MATERIAL"EMPTY"
PART_NUMBER"CS03322FB03"
CDS_LIB"pure_quanta"
WATTAGE"1/16W"
PACK_TYPE"0402LF"
TOLERANCE"1%"
LOCATION"R654"
$SEC"1"
CDS_SEC"1";
"B"
$PN"2"55;
"A"
$PN"1"61;
%"Q_RES"
"1","(3250,2150)","0","pure_quanta","I35";
;
VALUE"33.2"
MATERIAL"EMPTY"
PACK_TYPE"0402LF"
WATTAGE"1/16W"
CDS_LIB"pure_quanta"
TOLERANCE"1%"
PART_NUMBER"CS03322FB03"
LOCATION"R48"
$SEC"1"
CDS_SEC"1";
"B"
$PN"2"56;
"A"
$PN"1"39;
%"Q_RES"
"1","(3250,1850)","0","pure_quanta","I42";
;
PART_NUMBER"CS03322FB03"
MATERIAL"EMPTY"
VALUE"33.2"
WATTAGE"1/16W"
PACK_TYPE"0402LF"
CDS_LIB"pure_quanta"
TOLERANCE"1%"
LOCATION"R649"
$SEC"1"
CDS_SEC"1";
"B"
$PN"2"59;
"A"
$PN"1"20;
%"Q_RES"
"1","(3250,1950)","0","pure_quanta","I43";
;
MATERIAL"EMPTY"
VALUE"33.2"
PACK_TYPE"0402LF"
WATTAGE"1/16W"
CDS_LIB"pure_quanta"
TOLERANCE"1%"
PART_NUMBER"CS03322FB03"
LOCATION"R648"
$SEC"1"
CDS_SEC"1";
"B"
$PN"2"58;
"A"
$PN"1"19;
%"Q_RES"
"1","(3250,2000)","0","pure_quanta","I45";
;
MATERIAL"EMPTY"
VALUE"33.2"
CDS_LIB"pure_quanta"
WATTAGE"1/16W"
PACK_TYPE"0402LF"
TOLERANCE"1%"
PART_NUMBER"CS03322FB03"
LOCATION"R647"
$SEC"1"
CDS_SEC"1";
"B"
$PN"2"60;
"A"
$PN"1"18;
%"Q_RES"
"1","(3250,2100)","0","pure_quanta","I46";
;
MATERIAL"EMPTY"
VALUE"33.2"
CDS_LIB"pure_quanta"
WATTAGE"1/16W"
PACK_TYPE"0402LF"
TOLERANCE"1%"
PART_NUMBER"CS03322FB03"
LOCATION"R532"
$SEC"1"
CDS_SEC"1";
"B"
$PN"2"57;
"A"
$PN"1"40;
%"UNIVERSAL_POWER"
"1","(4100,75)","0","logical_power","I47";
;
HDL_POWER"P3V3_AUX"
CDS_LIB"logical_power";
"A"8;
%"Q_RES"
"1","(-2475,3975)","0","pure_quanta","I58";
;
MATERIAL"EMPTY"
VALUE"10K"
CDS_LIB"pure_quanta"
PART_NUMBER"TMP_QCS31002FB26"
TOLERANCE"1%"
WATTAGE"1/16W"
PACK_TYPE"0402LF"
LOCATION"R662"
$SEC"1"
CDS_SEC"1";
"B"
$PN"2"68;
"A"
$PN"1"2;
%"Q_RES"
"1","(-2475,3925)","0","pure_quanta","I59";
;
MATERIAL"EMPTY"
VALUE"10K"
CDS_LIB"pure_quanta"
PART_NUMBER"TMP_QCS31002FB26"
TOLERANCE"1%"
WATTAGE"1/16W"
PACK_TYPE"0402LF"
LOCATION"R663"
$SEC"1"
CDS_SEC"1";
"B"
$PN"2"67;
"A"
$PN"1"2;
%"Q_RES"
"1","(-2475,4025)","0","pure_quanta","I60";
;
MATERIAL"EMPTY"
VALUE"10K"
CDS_LIB"pure_quanta"
PART_NUMBER"TMP_QCS31002FB26"
TOLERANCE"1%"
WATTAGE"1/16W"
PACK_TYPE"0402LF"
LOCATION"R661"
$SEC"1"
CDS_SEC"1";
"B"
$PN"2"29;
"A"
$PN"1"2;
%"Q_RES"
"1","(-2475,4075)","0","pure_quanta","I61";
;
MATERIAL"EMPTY"
VALUE"10K"
CDS_LIB"pure_quanta"
PART_NUMBER"TMP_QCS31002FB26"
TOLERANCE"1%"
WATTAGE"1/16W"
PACK_TYPE"0402LF"
LOCATION"R660"
$SEC"1"
CDS_SEC"1";
"B"
$PN"2"23;
"A"
$PN"1"2;
%"Q_RES"
"1","(-2475,4175)","0","pure_quanta","I62";
;
MATERIAL"EMPTY"
VALUE"10K"
CDS_LIB"pure_quanta"
PART_NUMBER"TMP_QCS31002FB26"
TOLERANCE"1%"
WATTAGE"1/16W"
PACK_TYPE"0402LF"
LOCATION"R658"
$SEC"1"
CDS_SEC"1";
"B"
$PN"2"25;
"A"
$PN"1"2;
%"Q_RES"
"1","(-2475,4225)","0","pure_quanta","I63";
;
MATERIAL"EMPTY"
VALUE"10K"
CDS_LIB"pure_quanta"
PART_NUMBER"TMP_QCS31002FB26"
TOLERANCE"1%"
WATTAGE"1/16W"
PACK_TYPE"0402LF"
LOCATION"R657"
$SEC"1"
CDS_SEC"1";
"B"
$PN"2"24;
"A"
$PN"1"2;
%"Q_RES"
"1","(-2475,4125)","0","pure_quanta","I64";
;
MATERIAL"EMPTY"
VALUE"10K"
CDS_LIB"pure_quanta"
PART_NUMBER"TMP_QCS31002FB26"
TOLERANCE"1%"
WATTAGE"1/16W"
PACK_TYPE"0402LF"
LOCATION"R659"
$SEC"1"
CDS_SEC"1";
"B"
$PN"2"26;
"A"
$PN"1"2;
%"Q_RES"
"1","(-2475,4275)","0","pure_quanta","I66";
;
MATERIAL"EMPTY"
VALUE"10K"
CDS_LIB"pure_quanta"
PART_NUMBER"TMP_QCS31002FB26"
TOLERANCE"1%"
WATTAGE"1/16W"
PACK_TYPE"0402LF"
LOCATION"R656"
$SEC"1"
CDS_SEC"1";
"B"
$PN"2"27;
"A"
$PN"1"2;
%"Q_RES"
"1","(-2475,4325)","0","pure_quanta","I67";
;
MATERIAL"EMPTY"
WATTAGE"1/16W"
VALUE"10K"
PACK_TYPE"0402LF"
TOLERANCE"1%"
PART_NUMBER"TMP_QCS31002FB26"
CDS_LIB"pure_quanta"
LOCATION"R655"
$SEC"1"
CDS_SEC"1";
"B"
$PN"2"28;
"A"
$PN"1"2;
%"Q_CAP"
"1","(4500,-600)","0","pure_quanta","I80";
;
PACK_TYPE"0402"
MATERIAL"EMPTY"
TOLERANCE"10%"
VOLTAGE"25V"
PART_NUMBER"CH4104K1B00"
VALUE"0.1UF"
CDS_LIB"pure_quanta"
LOCATION"C235"
$SEC"1"
CDS_SEC"1";
"B"
$PN"2"9;
"A"
$PN"1"8;
%"Q_CAP"
"1","(4100,-600)","0","pure_quanta","I81";
;
PACK_TYPE"C0603"
VOLTAGE"10V"
VALUE"22UF"
PART_NUMBER"CH6222M9901"
MATERIAL"EMPTY"
TOLERANCE"20%"
CDS_LIB"pure_quanta"
LOCATION"C234"
$SEC"1"
CDS_SEC"1";
"B"
$PN"2"9;
"A"
$PN"1"8;
%"SCONN67_NASA0S6730TS67"
"1","(1525,2575)","0","pure_quanta","I84";
;
VALUE"SCONN67_NASA0-S6730-TS67"
PART_NUMBER"DFHS75FR133"
MATERIAL"IO"
PART_TYPE"SMLF"
CDS_LIB"pure_quanta"
NEEDS_NO_SIZE"TRUE"
CDS_LMAN_SYM_OUTLINE"-150,975,150,-975"
$LOCATION"J4"
CDS_LOCATION"J4"
$SEC"1"
CDS_SEC"1";
"G2"
$PN"G2"11;
"G1"
$PN"G1"10;
"75"
$PN"75"11;
"73"
$PN"73"0;
"71"
$PN"71"20;
"69"
$PN"69"11;
"67"
$PN"67"19;
"65"
$PN"65"18;
"63"
$PN"63"11;
"61"
$PN"61"40;
"59"
$PN"59"39;
"57"
$PN"57"11;
"55"
$PN"55"61;
"53"
$PN"53"0;
"51"
$PN"51"11;
"49"
$PN"49"0;
"47"
$PN"47"0;
"45"
$PN"45"11;
"43"
$PN"43"0;
"41"
$PN"41"0;
"39"
$PN"39"11;
"37"
$PN"37"54;
"35"
$PN"35"41;
"33"
$PN"33"11;
"31"
$PN"31"53;
"29"
$PN"29"11;
"27"
$PN"27"52;
"25"
$PN"25"51;
"23"
$PN"23"11;
"21"
$PN"21"50;
"19"
$PN"19"42;
"17"
$PN"17"0;
"7"
$PN"7"11;
"5"
$PN"5"49;
"3"
$PN"3"62;
"1"
$PN"1"11;
"74"
$PN"74"1;
"72"
$PN"72"1;
"70"
$PN"70"0;
"68"
$PN"68"0;
"66"
$PN"66"21;
"64"
$PN"64"0;
"62"
$PN"62"0;
"60"
$PN"60"0;
"58"
$PN"58"22;
"56"
$PN"56"17;
"54"
$PN"54"16;
"52"
$PN"52"48;
"50"
$PN"50"0;
"48"
$PN"48"0;
"46"
$PN"46"15;
"44"
$PN"44"0;
"42"
$PN"42"14;
"40"
$PN"40"32;
"38"
$PN"38"0;
"36"
$PN"36"10;
"34"
$PN"34"0;
"32"
$PN"32"0;
"30"
$PN"30"10;
"28"
$PN"28"13;
"26"
$PN"26"31;
"24"
$PN"24"10;
"22"
$PN"22"0;
"20"
$PN"20"0;
"18"
$PN"18"10;
"16"
$PN"16"30;
"6"
$PN"6"0;
"4"
$PN"4"1;
"2"
$PN"2"1;
%"Q_RES"
"1","(175,2250)","0","pure_quanta","I98";
;
MATERIAL"EMPTY"
VALUE"33.2"
PACK_TYPE"0402LF"
WATTAGE"1/16W"
CDS_LIB"pure_quanta"
TOLERANCE"1%"
PART_NUMBER"CS03322FB03"
LOCATION"R651"
$SEC"1"
CDS_SEC"1";
"B"
$PN"2"16;
"A"
$PN"1"35;
%"Q_RES"
"1","(175,2300)","0","pure_quanta","I99";
;
MATERIAL"EMPTY"
VALUE"33.2"
TOLERANCE"1%"
CDS_LIB"pure_quanta"
WATTAGE"1/16W"
PACK_TYPE"0402LF"
PART_NUMBER"CS03322FB03"
LOCATION"R650"
$SEC"1"
CDS_SEC"1";
"B"
$PN"2"48;
"A"
$PN"1"36;
END.
